(kicad_pcb
	(version 20241229)
	(generator "pcbnew")
	(generator_version "9.0")
	(general
		(thickness 1.6)
		(legacy_teardrops no)
	)
	(paper "A4")
	(title_block
		(title "GMSL Deserializer")
		(date "2025-10-09")
		(rev "1.0.4")
		(company "Antmicro Ltd")
		(comment 1 "www.antmicro.com")
		(comment 9 "footprints 144-145 of 235")
	)
	(layers
		(0 "F.Cu" signal)
		(4 "In1.Cu" power)
		(6 "In2.Cu" power)
		(2 "B.Cu" signal)
		(9 "F.Adhes" user "F.Adhesive")
		(11 "B.Adhes" user "B.Adhesive")
		(13 "F.Paste" user)
		(15 "B.Paste" user)
		(5 "F.SilkS" user "F.Silkscreen")
		(7 "B.SilkS" user "B.Silkscreen")
		(1 "F.Mask" user)
		(3 "B.Mask" user)
		(17 "Dwgs.User" user "User.Drawings")
		(19 "Cmts.User" user "User.Comments")
		(21 "Eco1.User" user "User.Eco1")
		(23 "Eco2.User" user "User.Eco2")
		(25 "Edge.Cuts" user)
		(27 "Margin" user)
		(31 "F.CrtYd" user "F.Courtyard")
		(29 "B.CrtYd" user "B.Courtyard")
		(35 "F.Fab" user)
		(33 "B.Fab" user)
	)
	(footprint "antmicro-footprints:C_0402_1005Metric"
		(layer "F.Cu")
		(at 120.832 85.956 -90)
		(descr "Capacitor SMD 0402")
		(tags "capacitor SMD 0402")
		(property "Reference" "C20"
			(at -0.205238 0.614176 90)
			(layer "F.SilkS")
			(effects
				(font
					(size 0.7 0.7)
					(thickness 0.15)
				)
				(justify right bottom)
			)
		)
		(property "Value" "C_100n_0402"
			(at -1.022927 2.155213 90)
			(layer "F.Fab")
			(effects
				(font
					(size 0.7 0.7)
					(thickness 0.15)
				)
				(justify right bottom)
			)
		)
		(property "Datasheet" "https://www.murata.com/products/productdetail?partno=GRM155R61H104KE14%23"
			(at 0 0 270)
			(layer "F.Fab")
			(hide yes)
			(effects
				(font
					(size 1.27 1.27)
					(thickness 0.15)
				)
			)
		)
		(property "Description" "SMD Multilayer Ceramic Capacitor, 0.1 µF, 50 V, 0402 [1005 Metric], ± 10%, X5R, GRM Series"
			(at 0 0 270)
			(layer "F.Fab")
			(hide yes)
			(effects
				(font
					(size 1.27 1.27)
					(thickness 0.15)
				)
			)
		)
		(property "Author" "Antmicro"
			(at 34.876 206.788 0)
			(layer "F.Fab")
			(hide yes)
			(effects
				(font
					(size 1 1)
					(thickness 0.15)
				)
			)
		)
		(property "Dielectric" "X5R"
			(at 34.876 206.788 0)
			(layer "F.Fab")
			(hide yes)
			(effects
				(font
					(size 1 1)
					(thickness 0.15)
				)
			)
		)
		(property "License" "Apache-2.0"
			(at 34.876 206.788 0)
			(layer "F.Fab")
			(hide yes)
			(effects
				(font
					(size 1 1)
					(thickness 0.15)
				)
			)
		)
		(property "MPN" "GRM155R61H104KE14D"
			(at 34.876 206.788 0)
			(layer "F.Fab")
			(hide yes)
			(effects
				(font
					(size 1 1)
					(thickness 0.15)
				)
			)
		)
		(property "Manufacturer" "Murata"
			(at 34.876 206.788 0)
			(layer "F.Fab")
			(hide yes)
			(effects
				(font
					(size 1 1)
					(thickness 0.15)
				)
			)
		)
		(property "Val" "100n"
			(at 34.876 206.788 0)
			(layer "F.Fab")
			(hide yes)
			(effects
				(font
					(size 1 1)
					(thickness 0.15)
				)
			)
		)
		(property "Voltage" "50V"
			(at 34.876 206.788 0)
			(layer "F.Fab")
			(hide yes)
			(effects
				(font
					(size 1 1)
					(thickness 0.15)
				)
			)
		)
		(sheetname "/Power/")
		(sheetfile "power.kicad_sch")
		(attr smd)
		(fp_rect
			(start -0.925 -0.47)
			(end 0.925 0.47)
			(stroke
				(width 0.05)
				(type default)
			)
			(fill no)
			(layer "F.CrtYd")
		)
		(fp_line
			(start -0.494 0.248)
			(end -0.494 -0.25)
			(stroke
				(width 0.15)
				(type solid)
			)
			(layer "F.Fab")
		)
		(fp_line
			(start 0.504 0.248)
			(end -0.494 0.248)
			(stroke
				(width 0.15)
				(type solid)
			)
			(layer "F.Fab")
		)
		(fp_line
			(start -0.494 -0.25)
			(end 0.504 -0.25)
			(stroke
				(width 0.15)
				(type solid)
			)
			(layer "F.Fab")
		)
		(fp_line
			(start 0.504 -0.25)
			(end 0.504 0.248)
			(stroke
				(width 0.15)
				(type solid)
			)
			(layer "F.Fab")
		)
		(pad "1" smd roundrect
			(at -0.48 0 270)
			(size 0.59 0.64)
			(layers "F.Cu" "F.Mask" "F.Paste")
			(roundrect_rratio 0.25)
			(net 8 "Net-(U5-BST)")
			(pintype "passive")
		)
		(pad "2" smd roundrect
			(at 0.48 0 270)
			(size 0.59 0.64)
			(layers "F.Cu" "F.Mask" "F.Paste")
			(roundrect_rratio 0.25)
			(net 9 "/Power/SW_1V2")
			(pintype "passive")
		)
	)
	(footprint "antmicro-footprints:R_0402_1005Metric"
		(layer "F.Cu")
		(at 170.18 64.135 90)
		(descr "Resistor SMD 0402")
		(tags "resistor SMD 0402")
		(property "Reference" "R2"
			(at -2.248717 0.3475 90)
			(layer "F.SilkS")
			(effects
				(font
					(size 0.7 0.7)
					(thickness 0.15)
				)
				(justify left bottom)
			)
		)
		(property "Value" "R_0R_0402"
			(at -1.011843 1.772047 90)
			(layer "F.Fab")
			(effects
				(font
					(size 0.7 0.7)
					(thickness 0.15)
				)
				(justify left bottom)
			)
		)
		(property "Datasheet" "https://industrial.panasonic.com/cdbs/www-data/pdf/RDA0000/AOA0000C301.pdf"
			(at 0 0 90)
			(layer "F.Fab")
			(hide yes)
			(effects
				(font
					(size 1.27 1.27)
					(thickness 0.15)
				)
			)
		)
		(property "Description" "SMD Chip Resistor, Jumper, 0 ohm, 100 mW, 0402 [1005 Metric], Thick Film, General Purpose"
			(at 0 0 90)
			(layer "F.Fab")
			(hide yes)
			(effects
				(font
					(size 1.27 1.27)
					(thickness 0.15)
				)
			)
		)
		(property "Author" "Antmicro"
			(at 234.315 -106.045 0)
			(layer "F.Fab")
			(hide yes)
			(effects
				(font
					(size 1 1)
					(thickness 0.15)
				)
			)
		)
		(property "Current" "1A"
			(at 234.315 -106.045 0)
			(layer "F.Fab")
			(hide yes)
			(effects
				(font
					(size 1 1)
					(thickness 0.15)
				)
			)
		)
		(property "License" "Apache-2.0"
			(at 234.315 -106.045 0)
			(layer "F.Fab")
			(hide yes)
			(effects
				(font
					(size 1 1)
					(thickness 0.15)
				)
			)
		)
		(property "MPN" "ERJ2GE0R00X"
			(at 234.315 -106.045 0)
			(layer "F.Fab")
			(hide yes)
			(effects
				(font
					(size 1 1)
					(thickness 0.15)
				)
			)
		)
		(property "Manufacturer" "Panasonic"
			(at 234.315 -106.045 0)
			(layer "F.Fab")
			(hide yes)
			(effects
				(font
					(size 1 1)
					(thickness 0.15)
				)
			)
		)
		(property "Tolerance" ""
			(at 234.315 -106.045 0)
			(layer "F.Fab")
			(hide yes)
			(effects
				(font
					(size 1 1)
					(thickness 0.15)
				)
			)
		)
		(property "Val" "0R"
			(at 234.315 -106.045 0)
			(layer "F.Fab")
			(hide yes)
			(effects
				(font
					(size 1 1)
					(thickness 0.15)
				)
			)
		)
		(sheetname "/Connectors/")
		(sheetfile "connectors.kicad_sch")
		(attr smd)
		(fp_rect
			(start -0.925 -0.47)
			(end 0.925 0.47)
			(stroke
				(width 0.05)
				(type default)
			)
			(fill no)
			(layer "F.CrtYd")
		)
		(fp_rect
			(start -0.5 -0.25)
			(end 0.5 0.25)
			(stroke
				(width 0.15)
				(type solid)
			)
			(fill no)
			(layer "F.Fab")
		)
		(pad "1" smd roundrect
			(at -0.48 0 90)
			(size 0.59 0.64)
			(layers "F.Cu" "F.Mask" "F.Paste")
			(roundrect_rratio 0.25)
			(net 80 "/Connectors/MFP0")
			(pintype "passive")
		)
		(pad "2" smd roundrect
			(at 0.48 0 90)
			(size 0.59 0.64)
			(layers "F.Cu" "F.Mask" "F.Paste")
			(roundrect_rratio 0.25)
			(net 130 "Net-(U1-Y)")
			(pintype "passive")
		)
	)
)
